(kicad_pcb
	(version 20241229)
	(generator "pcbnew")
	(generator_version "9.0")
	(general
		(thickness 1.62)
		(legacy_teardrops no)
	)
	(paper "A3")
	(title_block
		(title "COM Express 7 Baseboard")
		(date "2025-02-04")
		(rev "1.1.2")
		(company "Antmicro Ltd")
		(comment 1 "www.antmicro.com")
		(comment 9 "footprints 297-302 of 802")
	)
	(layers
		(0 "F.Cu" signal)
		(4 "In1.Cu" signal)
		(6 "In2.Cu" signal)
		(8 "In3.Cu" signal)
		(10 "In4.Cu" signal)
		(12 "In5.Cu" signal)
		(14 "In6.Cu" signal)
		(2 "B.Cu" signal)
		(9 "F.Adhes" user "F.Adhesive")
		(11 "B.Adhes" user "B.Adhesive")
		(13 "F.Paste" user)
		(15 "B.Paste" user)
		(5 "F.SilkS" user "F.Silkscreen")
		(7 "B.SilkS" user "B.Silkscreen")
		(1 "F.Mask" user)
		(3 "B.Mask" user)
		(17 "Dwgs.User" user "User.Drawings")
		(19 "Cmts.User" user "User.Comments")
		(21 "Eco1.User" user "User.Eco1")
		(23 "Eco2.User" user "User.Eco2")
		(25 "Edge.Cuts" user)
		(27 "Margin" user)
		(31 "F.CrtYd" user "F.Courtyard")
		(29 "B.CrtYd" user "B.Courtyard")
		(35 "F.Fab" user)
		(33 "B.Fab" user)
	)
	(footprint "antmicro-footprints:R_0402_1005Metric"
		(layer "F.Cu")
		(at 193.70861 77.152163 90)
		(descr "Resistor SMD 0402")
		(tags "resistor SMD 0402")
		(property "Reference" "R325"
			(at -1.9 -0.5 90)
			(layer "F.SilkS")
			(effects
				(font
					(size 0.7 0.7)
					(thickness 0.15)
				)
				(justify left bottom)
			)
		)
		(property "Value" "R_2k2_0402"
			(at -1.011843 1.772047 90)
			(layer "F.Fab")
			(effects
				(font
					(size 0.7 0.7)
					(thickness 0.15)
				)
				(justify left bottom)
			)
		)
		(property "Datasheet" "https://www.bourns.com/docs/product-datasheets/cr.pdf"
			(at 0 0 90)
			(layer "F.Fab")
			(hide yes)
			(effects
				(font
					(size 1.27 1.27)
					(thickness 0.15)
				)
			)
		)
		(property "Author" "Antmicro"
			(at 270.860773 -116.556447 0)
			(layer "F.Fab")
			(hide yes)
			(effects
				(font
					(size 1 1)
					(thickness 0.15)
				)
			)
		)
		(property "License" "Apache-2.0"
			(at 270.860773 -116.556447 0)
			(layer "F.Fab")
			(hide yes)
			(effects
				(font
					(size 1 1)
					(thickness 0.15)
				)
			)
		)
		(property "MPN" "CR0402-FX-2201GLF"
			(at 270.860773 -116.556447 0)
			(layer "F.Fab")
			(hide yes)
			(effects
				(font
					(size 1 1)
					(thickness 0.15)
				)
			)
		)
		(property "Manufacturer" "Bourns"
			(at 270.860773 -116.556447 0)
			(layer "F.Fab")
			(hide yes)
			(effects
				(font
					(size 1 1)
					(thickness 0.15)
				)
			)
		)
		(property "Tolerance" "1%"
			(at 270.860773 -116.556447 0)
			(layer "F.Fab")
			(hide yes)
			(effects
				(font
					(size 1 1)
					(thickness 0.15)
				)
			)
		)
		(property "Val" "2k2"
			(at 270.860773 -116.556447 0)
			(layer "F.Fab")
			(hide yes)
			(effects
				(font
					(size 1 1)
					(thickness 0.15)
				)
			)
		)
		(sheetname "Power")
		(sheetfile "power.kicad_sch")
		(attr smd)
		(fp_rect
			(start -0.925 -0.47)
			(end 0.925 0.47)
			(stroke
				(width 0.05)
				(type default)
			)
			(fill no)
			(layer "F.CrtYd")
		)
		(fp_rect
			(start -0.5 -0.25)
			(end 0.5 0.25)
			(stroke
				(width 0.15)
				(type solid)
			)
			(fill no)
			(layer "F.Fab")
		)
		(pad "1" smd roundrect
			(at -0.48 0 90)
			(size 0.59 0.64)
			(layers "F.Cu" "F.Mask" "F.Paste")
			(roundrect_rratio 0.25)
			(net 1 "GND")
			(pintype "passive")
			(teardrops
				(best_length_ratio 0.2)
				(max_length 1)
				(best_width_ratio 0.9)
				(max_width 2)
				(curved_edges yes)
				(filter_ratio 0.9)
				(enabled yes)
				(allow_two_segments yes)
				(prefer_zone_connections yes)
			)
		)
		(pad "2" smd roundrect
			(at 0.48 0 90)
			(size 0.59 0.64)
			(layers "F.Cu" "F.Mask" "F.Paste")
			(roundrect_rratio 0.25)
			(net 984 "Net-(D32-C)")
			(pintype "passive")
			(teardrops
				(best_length_ratio 0.2)
				(max_length 1)
				(best_width_ratio 0.9)
				(max_width 2)
				(curved_edges yes)
				(filter_ratio 0.9)
				(enabled yes)
				(allow_two_segments yes)
				(prefer_zone_connections yes)
			)
		)
	)
	(footprint "antmicro-footprints:R_0402_1005Metric"
		(layer "F.Cu")
		(at 155.299 158.11 180)
		(descr "Resistor SMD 0402")
		(tags "resistor SMD 0402")
		(property "Reference" "R43"
			(at -6.701 17.5 0)
			(layer "F.SilkS")
			(effects
				(font
					(size 0.7 0.7)
					(thickness 0.15)
				)
				(justify right bottom)
			)
		)
		(property "Value" "R_0R_0402"
			(at -1.011843 1.772047 0)
			(layer "F.Fab")
			(effects
				(font
					(size 0.7 0.7)
					(thickness 0.15)
				)
				(justify right bottom)
			)
		)
		(property "Datasheet" "https://industrial.panasonic.com/cdbs/www-data/pdf/RDA0000/AOA0000C301.pdf"
			(at 0 0 180)
			(layer "F.Fab")
			(hide yes)
			(effects
				(font
					(size 1.27 1.27)
					(thickness 0.15)
				)
			)
		)
		(property "Author" "Antmicro"
			(at 310.598 316.22 0)
			(layer "F.Fab")
			(hide yes)
			(effects
				(font
					(size 1 1)
					(thickness 0.15)
				)
			)
		)
		(property "Current" "1A"
			(at 310.598 316.22 0)
			(layer "F.Fab")
			(hide yes)
			(effects
				(font
					(size 1 1)
					(thickness 0.15)
				)
			)
		)
		(property "License" "Apache-2.0"
			(at 310.598 316.22 0)
			(layer "F.Fab")
			(hide yes)
			(effects
				(font
					(size 1 1)
					(thickness 0.15)
				)
			)
		)
		(property "MPN" "ERJ2GE0R00X"
			(at 310.598 316.22 0)
			(layer "F.Fab")
			(hide yes)
			(effects
				(font
					(size 1 1)
					(thickness 0.15)
				)
			)
		)
		(property "Manufacturer" "Panasonic"
			(at 310.598 316.22 0)
			(layer "F.Fab")
			(hide yes)
			(effects
				(font
					(size 1 1)
					(thickness 0.15)
				)
			)
		)
		(property "Public" "False"
			(at 310.598 316.22 0)
			(layer "F.Fab")
			(hide yes)
			(effects
				(font
					(size 1 1)
					(thickness 0.15)
				)
			)
		)
		(property "Tolerance" ""
			(at 310.598 316.22 0)
			(layer "F.Fab")
			(hide yes)
			(effects
				(font
					(size 1 1)
					(thickness 0.15)
				)
			)
		)
		(property "Val" "0R"
			(at 310.598 316.22 0)
			(layer "F.Fab")
			(hide yes)
			(effects
				(font
					(size 1 1)
					(thickness 0.15)
				)
			)
		)
		(sheetname "2xSFP+")
		(sheetfile "2xSFP+.kicad_sch")
		(attr smd)
		(fp_rect
			(start -0.925 -0.47)
			(end 0.925 0.47)
			(stroke
				(width 0.05)
				(type default)
			)
			(fill no)
			(layer "F.CrtYd")
		)
		(fp_rect
			(start -0.5 -0.25)
			(end 0.5 0.25)
			(stroke
				(width 0.15)
				(type solid)
			)
			(fill no)
			(layer "F.Fab")
		)
		(pad "1" smd roundrect
			(at -0.48 0 180)
			(size 0.59 0.64)
			(layers "F.Cu" "F.Mask" "F.Paste")
			(roundrect_rratio 0.25)
			(net 562 "/2xSFP+/~{LED0_0}")
			(pintype "passive")
			(teardrops
				(best_length_ratio 0.2)
				(max_length 1)
				(best_width_ratio 0.9)
				(max_width 2)
				(curved_edges yes)
				(filter_ratio 0.9)
				(enabled yes)
				(allow_two_segments yes)
				(prefer_zone_connections yes)
			)
		)
		(pad "2" smd roundrect
			(at 0.48 0 180)
			(size 0.59 0.64)
			(layers "F.Cu" "F.Mask" "F.Paste")
			(roundrect_rratio 0.25)
			(net 939 "/2xSFP+/SFP0_LEDY")
			(pintype "passive")
			(teardrops
				(best_length_ratio 0.2)
				(max_length 1)
				(best_width_ratio 0.9)
				(max_width 2)
				(curved_edges yes)
				(filter_ratio 0.9)
				(enabled yes)
				(allow_two_segments yes)
				(prefer_zone_connections yes)
			)
		)
	)
	(footprint "antmicro-footprints:R_0402_1005Metric"
		(layer "F.Cu")
		(at 289.85 102.86 180)
		(descr "Resistor SMD 0402")
		(tags "resistor SMD 0402")
		(property "Reference" "R115"
			(at -1.4 -2.35 0)
			(layer "F.SilkS")
			(effects
				(font
					(size 0.7 0.7)
					(thickness 0.15)
				)
				(justify right bottom)
			)
		)
		(property "Value" "R_0R_0402"
			(at -1.011843 1.772047 0)
			(layer "F.Fab")
			(effects
				(font
					(size 0.7 0.7)
					(thickness 0.15)
				)
				(justify right bottom)
			)
		)
		(property "Datasheet" "https://industrial.panasonic.com/cdbs/www-data/pdf/RDA0000/AOA0000C301.pdf"
			(at 0 0 180)
			(layer "F.Fab")
			(hide yes)
			(effects
				(font
					(size 1.27 1.27)
					(thickness 0.15)
				)
			)
		)
		(property "Author" "Antmicro"
			(at 579.7 205.72 0)
			(layer "F.Fab")
			(hide yes)
			(effects
				(font
					(size 1 1)
					(thickness 0.15)
				)
			)
		)
		(property "Current" "1A"
			(at 579.7 205.72 0)
			(layer "F.Fab")
			(hide yes)
			(effects
				(font
					(size 1 1)
					(thickness 0.15)
				)
			)
		)
		(property "License" "Apache-2.0"
			(at 579.7 205.72 0)
			(layer "F.Fab")
			(hide yes)
			(effects
				(font
					(size 1 1)
					(thickness 0.15)
				)
			)
		)
		(property "MPN" "ERJ2GE0R00X"
			(at 579.7 205.72 0)
			(layer "F.Fab")
			(hide yes)
			(effects
				(font
					(size 1 1)
					(thickness 0.15)
				)
			)
		)
		(property "Manufacturer" "Panasonic"
			(at 579.7 205.72 0)
			(layer "F.Fab")
			(hide yes)
			(effects
				(font
					(size 1 1)
					(thickness 0.15)
				)
			)
		)
		(property "Public" "False"
			(at 579.7 205.72 0)
			(layer "F.Fab")
			(hide yes)
			(effects
				(font
					(size 1 1)
					(thickness 0.15)
				)
			)
		)
		(property "Tolerance" ""
			(at 579.7 205.72 0)
			(layer "F.Fab")
			(hide yes)
			(effects
				(font
					(size 1 1)
					(thickness 0.15)
				)
			)
		)
		(property "Val" "0R"
			(at 579.7 205.72 0)
			(layer "F.Fab")
			(hide yes)
			(effects
				(font
					(size 1 1)
					(thickness 0.15)
				)
			)
		)
		(sheetname "Power")
		(sheetfile "power.kicad_sch")
		(attr smd dnp)
		(fp_rect
			(start -0.925 -0.47)
			(end 0.925 0.47)
			(stroke
				(width 0.05)
				(type default)
			)
			(fill no)
			(layer "F.CrtYd")
		)
		(fp_rect
			(start -0.5 -0.25)
			(end 0.5 0.25)
			(stroke
				(width 0.15)
				(type solid)
			)
			(fill no)
			(layer "F.Fab")
		)
		(pad "1" smd roundrect
			(at -0.48 0 180)
			(size 0.59 0.64)
			(layers "F.Cu" "F.Mask" "F.Paste")
			(roundrect_rratio 0.25)
			(net 528 "/Backplane/~{PERST}")
			(pintype "passive")
			(teardrops
				(best_length_ratio 0.2)
				(max_length 1)
				(best_width_ratio 0.9)
				(max_width 2)
				(curved_edges yes)
				(filter_ratio 0.9)
				(enabled yes)
				(allow_two_segments yes)
				(prefer_zone_connections yes)
			)
		)
		(pad "2" smd roundrect
			(at 0.48 0 180)
			(size 0.59 0.64)
			(layers "F.Cu" "F.Mask" "F.Paste")
			(roundrect_rratio 0.25)
			(net 535 "Net-(Q3-G)")
			(pintype "passive")
			(teardrops
				(best_length_ratio 0.2)
				(max_length 1)
				(best_width_ratio 0.9)
				(max_width 2)
				(curved_edges yes)
				(filter_ratio 0.9)
				(enabled yes)
				(allow_two_segments yes)
				(prefer_zone_connections yes)
			)
		)
	)
	(footprint "antmicro-footprints:Mech_M2_2230_H2.5mm"
		(layer "F.Cu")
		(at 120.0745 80.3095 90)
		(property "Reference" "A4"
			(at -0.001 -12.11 90)
			(layer "F.SilkS")
			(hide yes)
			(effects
				(font
					(size 0.7 0.7)
					(thickness 0.15)
				)
				(justify right bottom)
			)
		)
		(property "Value" "Mech_M2_2230_H2.5mm"
			(at -0.001 6.857 90)
			(layer "F.Fab")
			(effects
				(font
					(size 0.7 0.7)
					(thickness 0.15)
				)
				(justify right bottom)
			)
		)
		(property "Author" "Antmicro"
			(at 200.384 -39.765 0)
			(layer "F.Fab")
			(hide yes)
			(effects
				(font
					(size 1 1)
					(thickness 0.15)
				)
			)
		)
		(property "License" "Apache-2.0"
			(at 200.384 -39.765 0)
			(layer "F.Fab")
			(hide yes)
			(effects
				(font
					(size 1 1)
					(thickness 0.15)
				)
			)
		)
		(property "MPN" ""
			(at 200.384 -39.765 0)
			(layer "F.Fab")
			(hide yes)
			(effects
				(font
					(size 1 1)
					(thickness 0.15)
				)
			)
		)
		(property "Manufacturer" "None"
			(at 200.384 -39.765 0)
			(layer "F.Fab")
			(hide yes)
			(effects
				(font
					(size 1 1)
					(thickness 0.15)
				)
			)
		)
		(property "Public" "False"
			(at 200.384 -39.765 0)
			(layer "F.Fab")
			(hide yes)
			(effects
				(font
					(size 1 1)
					(thickness 0.15)
				)
			)
		)
		(sheetname "M.2 key E")
		(sheetfile "m2keye.kicad_sch")
		(attr exclude_from_pos_files exclude_from_bom allow_missing_courtyard dnp)
	)
	(footprint "antmicro-footprints:R_0402_1005Metric"
		(layer "F.Cu")
		(at 155.299 160.11 180)
		(descr "Resistor SMD 0402")
		(tags "resistor SMD 0402")
		(property "Reference" "R45"
			(at -6.701 17.5 0)
			(layer "F.SilkS")
			(effects
				(font
					(size 0.7 0.7)
					(thickness 0.15)
				)
				(justify right bottom)
			)
		)
		(property "Value" "R_0R_0402"
			(at -1.011843 1.772047 0)
			(layer "F.Fab")
			(effects
				(font
					(size 0.7 0.7)
					(thickness 0.15)
				)
				(justify right bottom)
			)
		)
		(property "Datasheet" "https://industrial.panasonic.com/cdbs/www-data/pdf/RDA0000/AOA0000C301.pdf"
			(at 0 0 180)
			(layer "F.Fab")
			(hide yes)
			(effects
				(font
					(size 1.27 1.27)
					(thickness 0.15)
				)
			)
		)
		(property "Author" "Antmicro"
			(at 310.598 320.22 0)
			(layer "F.Fab")
			(hide yes)
			(effects
				(font
					(size 1 1)
					(thickness 0.15)
				)
			)
		)
		(property "Current" "1A"
			(at 310.598 320.22 0)
			(layer "F.Fab")
			(hide yes)
			(effects
				(font
					(size 1 1)
					(thickness 0.15)
				)
			)
		)
		(property "License" "Apache-2.0"
			(at 310.598 320.22 0)
			(layer "F.Fab")
			(hide yes)
			(effects
				(font
					(size 1 1)
					(thickness 0.15)
				)
			)
		)
		(property "MPN" "ERJ2GE0R00X"
			(at 310.598 320.22 0)
			(layer "F.Fab")
			(hide yes)
			(effects
				(font
					(size 1 1)
					(thickness 0.15)
				)
			)
		)
		(property "Manufacturer" "Panasonic"
			(at 310.598 320.22 0)
			(layer "F.Fab")
			(hide yes)
			(effects
				(font
					(size 1 1)
					(thickness 0.15)
				)
			)
		)
		(property "Public" "False"
			(at 310.598 320.22 0)
			(layer "F.Fab")
			(hide yes)
			(effects
				(font
					(size 1 1)
					(thickness 0.15)
				)
			)
		)
		(property "Tolerance" ""
			(at 310.598 320.22 0)
			(layer "F.Fab")
			(hide yes)
			(effects
				(font
					(size 1 1)
					(thickness 0.15)
				)
			)
		)
		(property "Val" "0R"
			(at 310.598 320.22 0)
			(layer "F.Fab")
			(hide yes)
			(effects
				(font
					(size 1 1)
					(thickness 0.15)
				)
			)
		)
		(sheetname "2xSFP+")
		(sheetfile "2xSFP+.kicad_sch")
		(attr smd dnp)
		(fp_rect
			(start -0.925 -0.47)
			(end 0.925 0.47)
			(stroke
				(width 0.05)
				(type default)
			)
			(fill no)
			(layer "F.CrtYd")
		)
		(fp_rect
			(start -0.5 -0.25)
			(end 0.5 0.25)
			(stroke
				(width 0.15)
				(type solid)
			)
			(fill no)
			(layer "F.Fab")
		)
		(pad "1" smd roundrect
			(at -0.48 0 180)
			(size 0.59 0.64)
			(layers "F.Cu" "F.Mask" "F.Paste")
			(roundrect_rratio 0.25)
			(net 564 "/2xSFP+/~{LED0_2}")
			(pintype "passive")
			(teardrops
				(best_length_ratio 0.2)
				(max_length 1)
				(best_width_ratio 0.9)
				(max_width 2)
				(curved_edges yes)
				(filter_ratio 0.9)
				(enabled yes)
				(allow_two_segments yes)
				(prefer_zone_connections yes)
			)
		)
		(pad "2" smd roundrect
			(at 0.48 0 180)
			(size 0.59 0.64)
			(layers "F.Cu" "F.Mask" "F.Paste")
			(roundrect_rratio 0.25)
			(net 931 "/2xSFP+/SFP0_LEDG")
			(pintype "passive")
			(teardrops
				(best_length_ratio 0.2)
				(max_length 1)
				(best_width_ratio 0.9)
				(max_width 2)
				(curved_edges yes)
				(filter_ratio 0.9)
				(enabled yes)
				(allow_two_segments yes)
				(prefer_zone_connections yes)
			)
		)
	)
	(footprint "antmicro-footprints:C_0402_1005Metric"
		(layer "F.Cu")
		(at 299.05 101.571 -90)
		(descr "Capacitor SMD 0402")
		(tags "capacitor SMD 0402")
		(property "Reference" "C69"
			(at -2.961 -0.4 90)
			(layer "F.SilkS")
			(effects
				(font
					(size 0.7 0.7)
					(thickness 0.15)
				)
				(justify right bottom)
			)
		)
		(property "Value" "C_1u_0402"
			(at -1.022927 2.155213 90)
			(layer "F.Fab")
			(effects
				(font
					(size 0.7 0.7)
					(thickness 0.15)
				)
				(justify right bottom)
			)
		)
		(property "Datasheet" "https://product.tdk.com/en/search/capacitor/ceramic/mlcc/info?part_no=C1005X6S1A105K050BC"
			(at 0 0 270)
			(layer "F.Fab")
			(hide yes)
			(effects
				(font
					(size 1.27 1.27)
					(thickness 0.15)
				)
			)
		)
		(property "Author" "Antmicro"
			(at 197.479 400.621 0)
			(layer "F.Fab")
			(hide yes)
			(effects
				(font
					(size 1 1)
					(thickness 0.15)
				)
			)
		)
		(property "Dielectric" ""
			(at 197.479 400.621 0)
			(layer "F.Fab")
			(hide yes)
			(effects
				(font
					(size 1 1)
					(thickness 0.15)
				)
			)
		)
		(property "License" "Apache-2.0"
			(at 197.479 400.621 0)
			(layer "F.Fab")
			(hide yes)
			(effects
				(font
					(size 1 1)
					(thickness 0.15)
				)
			)
		)
		(property "MPN" "C1005X6S1A105K050BC"
			(at 197.479 400.621 0)
			(layer "F.Fab")
			(hide yes)
			(effects
				(font
					(size 1 1)
					(thickness 0.15)
				)
			)
		)
		(property "Manufacturer" "TDK"
			(at 197.479 400.621 0)
			(layer "F.Fab")
			(hide yes)
			(effects
				(font
					(size 1 1)
					(thickness 0.15)
				)
			)
		)
		(property "Public" "False"
			(at 197.479 400.621 0)
			(layer "F.Fab")
			(hide yes)
			(effects
				(font
					(size 1 1)
					(thickness 0.15)
				)
			)
		)
		(property "Val" "1u"
			(at 197.479 400.621 0)
			(layer "F.Fab")
			(hide yes)
			(effects
				(font
					(size 1 1)
					(thickness 0.15)
				)
			)
		)
		(property "Voltage" ""
			(at 197.479 400.621 0)
			(layer "F.Fab")
			(hide yes)
			(effects
				(font
					(size 1 1)
					(thickness 0.15)
				)
			)
		)
		(sheetname "Power")
		(sheetfile "power.kicad_sch")
		(attr smd)
		(fp_rect
			(start -0.925 -0.47)
			(end 0.925 0.47)
			(stroke
				(width 0.05)
				(type default)
			)
			(fill no)
			(layer "F.CrtYd")
		)
		(fp_line
			(start -0.494 0.248)
			(end -0.494 -0.25)
			(stroke
				(width 0.15)
				(type solid)
			)
			(layer "F.Fab")
		)
		(fp_line
			(start 0.504 0.248)
			(end -0.494 0.248)
			(stroke
				(width 0.15)
				(type solid)
			)
			(layer "F.Fab")
		)
		(fp_line
			(start -0.494 -0.25)
			(end 0.504 -0.25)
			(stroke
				(width 0.15)
				(type solid)
			)
			(layer "F.Fab")
		)
		(fp_line
			(start 0.504 -0.25)
			(end 0.504 0.248)
			(stroke
				(width 0.15)
				(type solid)
			)
			(layer "F.Fab")
		)
		(pad "1" smd roundrect
			(at -0.48 0 270)
			(size 0.59 0.64)
			(layers "F.Cu" "F.Mask" "F.Paste")
			(roundrect_rratio 0.25)
			(net 1 "GND")
			(pintype "passive")
			(teardrops
				(best_length_ratio 0.2)
				(max_length 1)
				(best_width_ratio 0.9)
				(max_width 2)
				(curved_edges yes)
				(filter_ratio 0.9)
				(enabled yes)
				(allow_two_segments yes)
				(prefer_zone_connections yes)
			)
		)
		(pad "2" smd roundrect
			(at 0.48 0 270)
			(size 0.59 0.64)
			(layers "F.Cu" "F.Mask" "F.Paste")
			(roundrect_rratio 0.25)
			(net 79 "Net-(U23-VOUT)")
			(pintype "passive")
			(teardrops
				(best_length_ratio 0.2)
				(max_length 1)
				(best_width_ratio 0.9)
				(max_width 2)
				(curved_edges yes)
				(filter_ratio 0.9)
				(enabled yes)
				(allow_two_segments yes)
				(prefer_zone_connections yes)
			)
		)
	)
)
